(kicad_pcb
	(version 20260206)
	(generator "pcbnew")
	(generator_version "10.0")
	(general
		(thickness 1.6)
		(legacy_teardrops no)
	)
	(paper "A4")
	(title_block
		(title "Bryce Canyon_R.DPB_16317-1_OCP.brd")
		(comment 1 "Bryce Canyon / footprints 386-392 of 2099")
	)
	(layers
		(0 "F.Cu" signal "TOP")
		(4 "In1.Cu" signal "L2GND")
		(6 "In2.Cu" signal "L3")
		(8 "In3.Cu" signal "L4VCC")
		(10 "In4.Cu" signal "L5VCC")
		(12 "In5.Cu" signal "L6")
		(14 "In6.Cu" signal "L7GND")
		(2 "B.Cu" signal "BOTTOM")
		(9 "F.Adhes" user "F.Adhesive")
		(11 "B.Adhes" user "B.Adhesive")
		(13 "F.Paste" user "Package Geometry/Pastemask Top")
		(15 "B.Paste" user "Package Geometry/Pastemask Bottom")
		(5 "F.SilkS" user "Ref Des/Silkscreen Top")
		(7 "B.SilkS" user "Ref Des/Silkscreen Bottom")
		(1 "F.Mask" user "Board Geometry/Soldermask Top")
		(3 "B.Mask" user "Board Geometry/Soldermask Bottom")
		(17 "Dwgs.User" user "User.Drawings")
		(19 "Cmts.User" user "User.Comments")
		(21 "Eco1.User" user "User.Eco1")
		(23 "Eco2.User" user "User.Eco2")
		(25 "Edge.Cuts" user "Board Geometry/Outline")
		(27 "Margin" user)
		(31 "F.CrtYd" user "Package Geometry/Place Bound Top")
		(29 "B.CrtYd" user "Package Geometry/Place Bound Bottom")
		(35 "F.Fab" user "Ref Des/Assembly Top")
		(33 "B.Fab" user "Ref Des/Assembly Bottom")
	)
	(footprint ""
		(layer "F.Cu")
		(at 180.975 -368.2238 90)
		(property "Reference" "C1"
			(at 0 0 90)
			(layer "F.SilkS")
			(hide yes)
			(effects
				(font
					(size 1.27 1.27)
				)
			)
		)
		(property "Value" "SCD1U25V2KX-2-GP"
			(at 1.1811 -2.7051 90)
			(unlocked yes)
			(layer "F.Fab")
			(hide yes)
			(effects
				(font
					(size 1.016 1.016)
					(thickness 0.1524)
				)
			)
		)
		(property "Device Type" "C402H22"
			(at 1.1811 -4.2291 90)
			(unlocked yes)
			(layer "F.Fab")
			(hide yes)
			(effects
				(font
					(size 1.016 1.016)
					(thickness 0.1524)
				)
			)
		)
		(duplicate_pad_numbers_are_jumpers no)
		(fp_rect
			(start -0.4318 0.9525)
			(end 0.4318 -0.9525)
			(stroke
				(width 0)
				(type default)
			)
			(fill no)
			(layer "F.CrtYd")
		)
		(fp_rect
			(start -0.4318 0.9525)
			(end 0.4318 -0.9525)
			(stroke
				(width 0)
				(type default)
			)
			(fill no)
			(layer "F.Fab")
		)
		(pad "1" smd custom
			(at 0 -0.4445 90)
			(size 0.1524 0.1524)
			(layers "F.Cu" "F.Mask" "F.Paste")
			(net "MB0_HS_ENABLE")
			(options
				(clearance outline)
				(anchor circle)
			)
			(primitives
				(gr_poly
					(pts
						(arc
							(start 0.3048 -0.2032)
							(mid 0.275042 -0.275042)
							(end 0.2032 -0.3048)
						)
						(arc
							(start -0.2032 -0.3048)
							(mid -0.275042 -0.275042)
							(end -0.3048 -0.2032)
						)
						(arc
							(start -0.3048 0.2032)
							(mid -0.275042 0.275042)
							(end -0.2032 0.3048)
						)
						(arc
							(start 0.2032 0.3048)
							(mid 0.275042 0.275042)
							(end 0.3048 0.2032)
						)
					)
					(width 0)
					(fill yes)
				)
			)
		)
		(pad "2" smd custom
			(at 0 0.4445 90)
			(size 0.1524 0.1524)
			(layers "F.Cu" "F.Mask" "F.Paste")
			(net "GND")
			(options
				(clearance outline)
				(anchor circle)
			)
			(primitives
				(gr_poly
					(pts
						(arc
							(start 0.3048 -0.2032)
							(mid 0.275042 -0.275042)
							(end 0.2032 -0.3048)
						)
						(arc
							(start -0.2032 -0.3048)
							(mid -0.275042 -0.275042)
							(end -0.3048 -0.2032)
						)
						(arc
							(start -0.3048 0.2032)
							(mid -0.275042 0.275042)
							(end -0.2032 0.3048)
						)
						(arc
							(start 0.2032 0.3048)
							(mid 0.275042 0.275042)
							(end 0.3048 0.2032)
						)
					)
					(width 0)
					(fill yes)
				)
			)
		)
	)
	(footprint ""
		(layer "F.Cu")
		(at 323.58965 -248.750074 -90)
		(property "Reference" "VIA14"
			(at 0 0 270)
			(layer "F.SilkS")
			(hide yes)
			(effects
				(font
					(size 1.27 1.27)
				)
			)
		)
		(property "Value" "100OHM-8L-2D36MM-L16-GP"
			(at -3.4036 -0.4572 270)
			(unlocked yes)
			(layer "F.Fab")
			(hide yes)
			(effects
				(font
					(size 1.016 1.016)
					(thickness 0.1524)
				)
			)
		)
		(property "Device Type" "VIA-PCIE-4P-427097"
			(at -3.4036 -1.9812 270)
			(unlocked yes)
			(layer "F.Fab")
			(hide yes)
			(effects
				(font
					(size 1.016 1.016)
					(thickness 0.1524)
				)
			)
		)
		(duplicate_pad_numbers_are_jumpers no)
		(fp_rect
			(start -2.1336 0.4826)
			(end 2.1336 -0.4826)
			(stroke
				(width 0)
				(type default)
			)
			(fill no)
			(layer "F.CrtYd")
		)
		(fp_rect
			(start -2.1336 0.4826)
			(end 2.1336 -0.4826)
			(stroke
				(width 0)
				(type default)
			)
			(fill no)
			(layer "F.Fab")
		)
		(pad "1" thru_hole circle
			(at -1.651 0 270)
			(size 0.508 0.508)
			(drill 0.254)
			(layers "*.Cu" "*.Mask")
			(remove_unused_layers no)
			(net "GND")
			(clearance 0.2286)
			(thermal_gap 0.2286)
		)
		(pad "2" thru_hole circle
			(at -0.635 0 270)
			(size 0.508 0.508)
			(drill 0.254)
			(layers "*.Cu" "*.Mask")
			(remove_unused_layers no)
			(net "PHY_DRV_B_TO_SCC_B_6_DP")
			(clearance 0.2286)
			(thermal_gap 0.2286)
		)
		(pad "3" thru_hole circle
			(at 0.635 0 270)
			(size 0.508 0.508)
			(drill 0.254)
			(layers "*.Cu" "*.Mask")
			(remove_unused_layers no)
			(net "PHY_DRV_B_TO_SCC_B_6_DN")
			(clearance 0.2286)
			(thermal_gap 0.2286)
		)
		(pad "4" thru_hole circle
			(at 1.651 0 270)
			(size 0.508 0.508)
			(drill 0.254)
			(layers "*.Cu" "*.Mask")
			(remove_unused_layers no)
			(net "GND")
			(clearance 0.2286)
			(thermal_gap 0.2286)
		)
	)
	(footprint ""
		(layer "F.Cu")
		(at 181.483 -263.271)
		(property "Reference" "R238"
			(at 0 0 0)
			(layer "F.SilkS")
			(hide yes)
			(effects
				(font
					(size 1.27 1.27)
				)
			)
		)
		(property "Value" "2R6F-GP"
			(at -0.0508 -4.8514 0)
			(unlocked yes)
			(layer "F.Fab")
			(hide yes)
			(effects
				(font
					(size 1.016 1.016)
					(thickness 0.1524)
				)
			)
		)
		(property "Device Type" "R1206H26"
			(at 0 -6.3754 0)
			(unlocked yes)
			(layer "F.Fab")
			(hide yes)
			(effects
				(font
					(size 1.016 1.016)
					(thickness 0.1524)
				)
			)
		)
		(duplicate_pad_numbers_are_jumpers no)
		(fp_line
			(start -1.016 -2.2352)
			(end 1.016 -2.2352)
			(stroke
				(width 0.1524)
				(type default)
			)
			(layer "F.SilkS")
		)
		(fp_line
			(start -1.016 2.2352)
			(end -1.016 -2.2352)
			(stroke
				(width 0.1524)
				(type default)
			)
			(layer "F.SilkS")
		)
		(fp_line
			(start 1.016 -2.2352)
			(end 1.016 2.2352)
			(stroke
				(width 0.1524)
				(type default)
			)
			(layer "F.SilkS")
		)
		(fp_line
			(start 1.016 2.2352)
			(end -1.016 2.2352)
			(stroke
				(width 0.1524)
				(type default)
			)
			(layer "F.SilkS")
		)
		(fp_rect
			(start -1.0922 2.3114)
			(end 1.0922 -2.3114)
			(stroke
				(width 0)
				(type default)
			)
			(fill no)
			(layer "F.CrtYd")
		)
		(fp_poly
			(pts
				(xy -1.0922 -2.3114) (xy 1.0922 -2.3114) (xy 1.0922 2.3114) (xy -1.0922 2.3114)
			)
			(stroke
				(width 0)
				(type default)
			)
			(fill no)
			(layer "F.Fab")
		)
		(pad "1" smd rect
			(at 0 -1.397)
			(size 1.651 1.27)
			(layers "F.Cu" "F.Mask" "F.Paste")
			(net "P5V_HDD5")
		)
		(pad "2" smd rect
			(at 0 1.397)
			(size 1.651 1.27)
			(layers "F.Cu" "F.Mask" "F.Paste")
			(net "5V_PRE_5")
		)
	)
	(footprint ""
		(layer "F.Cu")
		(at 370.205 -257.81 -90)
		(property "Reference" "R281"
			(at 0 0 270)
			(layer "F.SilkS")
			(hide yes)
			(effects
				(font
					(size 1.27 1.27)
				)
			)
		)
		(property "Value" "300KR2F-GP"
			(at 0.064008 -3.993896 270)
			(unlocked yes)
			(layer "F.Fab")
			(hide yes)
			(effects
				(font
					(size 1.016 1.016)
					(thickness 0.1524)
				)
			)
		)
		(property "Device Type" "R402H16"
			(at 0.064008 -5.517896 270)
			(unlocked yes)
			(layer "F.Fab")
			(hide yes)
			(effects
				(font
					(size 1.016 1.016)
					(thickness 0.1524)
				)
			)
		)
		(duplicate_pad_numbers_are_jumpers no)
		(fp_line
			(start -0.508 -0.9398)
			(end -0.508 0.9398)
			(stroke
				(width 0.1524)
				(type default)
			)
			(layer "F.SilkS")
		)
		(fp_line
			(start 0.508 -0.9398)
			(end -0.508 -0.9398)
			(stroke
				(width 0.1524)
				(type default)
			)
			(layer "F.SilkS")
		)
		(fp_rect
			(start -0.508 0.9398)
			(end 0.508 -0.9398)
			(stroke
				(width 0)
				(type default)
			)
			(fill no)
			(layer "F.CrtYd")
		)
		(fp_rect
			(start -0.508 0.9398)
			(end 0.508 -0.9398)
			(stroke
				(width 0)
				(type default)
			)
			(fill no)
			(layer "F.Fab")
		)
		(pad "1" smd custom
			(at 0 -0.4445 270)
			(size 0.1397 0.1397)
			(layers "F.Cu" "F.Mask" "F.Paste")
			(net "SW_HDD_N7")
			(options
				(clearance outline)
				(anchor circle)
			)
			(primitives
				(gr_poly
					(pts
						(arc
							(start -0.1778 -0.2794)
							(mid -0.249642 -0.249642)
							(end -0.2794 -0.1778)
						)
						(arc
							(start -0.2794 0.1778)
							(mid -0.249642 0.249642)
							(end -0.1778 0.2794)
						)
						(arc
							(start 0.1778 0.2794)
							(mid 0.249642 0.249642)
							(end 0.2794 0.1778)
						)
						(arc
							(start 0.2794 -0.1778)
							(mid 0.249642 -0.249642)
							(end 0.1778 -0.2794)
						)
					)
					(width 0)
					(fill yes)
				)
			)
		)
		(pad "2" smd custom
			(at 0 0.4445 270)
			(size 0.1397 0.1397)
			(layers "F.Cu" "F.Mask" "F.Paste")
			(net "P12V_B")
			(options
				(clearance outline)
				(anchor circle)
			)
			(primitives
				(gr_poly
					(pts
						(arc
							(start -0.1778 -0.2794)
							(mid -0.249642 -0.249642)
							(end -0.2794 -0.1778)
						)
						(arc
							(start -0.2794 0.1778)
							(mid -0.249642 0.249642)
							(end -0.1778 0.2794)
						)
						(arc
							(start 0.1778 0.2794)
							(mid 0.249642 0.249642)
							(end 0.2794 0.1778)
						)
						(arc
							(start 0.2794 -0.1778)
							(mid 0.249642 -0.249642)
							(end 0.1778 -0.2794)
						)
					)
					(width 0)
					(fill yes)
				)
			)
		)
	)
	(footprint ""
		(layer "F.Cu")
		(at 447.8782 -261.6454)
		(property "Reference" "C167"
			(at 0 0 0)
			(layer "F.SilkS")
			(hide yes)
			(effects
				(font
					(size 1.27 1.27)
				)
			)
		)
		(property "Value" "SCD01U50V2KX-1GP"
			(at 1.1811 -2.7051 0)
			(unlocked yes)
			(layer "F.Fab")
			(hide yes)
			(effects
				(font
					(size 1.016 1.016)
					(thickness 0.1524)
				)
			)
		)
		(property "Device Type" "C402H22"
			(at 1.1811 -4.2291 0)
			(unlocked yes)
			(layer "F.Fab")
			(hide yes)
			(effects
				(font
					(size 1.016 1.016)
					(thickness 0.1524)
				)
			)
		)
		(duplicate_pad_numbers_are_jumpers no)
		(fp_rect
			(start -0.4318 0.9525)
			(end 0.4318 -0.9525)
			(stroke
				(width 0)
				(type default)
			)
			(fill no)
			(layer "F.CrtYd")
		)
		(fp_rect
			(start -0.4318 0.9525)
			(end 0.4318 -0.9525)
			(stroke
				(width 0)
				(type default)
			)
			(fill no)
			(layer "F.Fab")
		)
		(pad "1" smd custom
			(at 0 -0.4445)
			(size 0.1524 0.1524)
			(layers "F.Cu" "F.Mask" "F.Paste")
			(net "HDD_PRSNT_10")
			(options
				(clearance outline)
				(anchor circle)
			)
			(primitives
				(gr_poly
					(pts
						(arc
							(start 0.3048 -0.2032)
							(mid 0.275042 -0.275042)
							(end 0.2032 -0.3048)
						)
						(arc
							(start -0.2032 -0.3048)
							(mid -0.275042 -0.275042)
							(end -0.3048 -0.2032)
						)
						(arc
							(start -0.3048 0.2032)
							(mid -0.275042 0.275042)
							(end -0.2032 0.3048)
						)
						(arc
							(start 0.2032 0.3048)
							(mid 0.275042 0.275042)
							(end 0.3048 0.2032)
						)
					)
					(width 0)
					(fill yes)
				)
			)
		)
		(pad "2" smd custom
			(at 0 0.4445)
			(size 0.1524 0.1524)
			(layers "F.Cu" "F.Mask" "F.Paste")
			(net "GND")
			(options
				(clearance outline)
				(anchor circle)
			)
			(primitives
				(gr_poly
					(pts
						(arc
							(start 0.3048 -0.2032)
							(mid 0.275042 -0.275042)
							(end 0.2032 -0.3048)
						)
						(arc
							(start -0.2032 -0.3048)
							(mid -0.275042 -0.275042)
							(end -0.3048 -0.2032)
						)
						(arc
							(start -0.3048 0.2032)
							(mid -0.275042 0.275042)
							(end -0.2032 0.3048)
						)
						(arc
							(start 0.2032 0.3048)
							(mid 0.275042 0.275042)
							(end 0.3048 0.2032)
						)
					)
					(width 0)
					(fill yes)
				)
			)
		)
	)
	(footprint ""
		(layer "F.Cu")
		(at 118.364 -263.271)
		(property "Reference" "R206"
			(at 0 0 0)
			(layer "F.SilkS")
			(hide yes)
			(effects
				(font
					(size 1.27 1.27)
				)
			)
		)
		(property "Value" "2R6F-GP"
			(at -0.0508 -4.8514 0)
			(unlocked yes)
			(layer "F.Fab")
			(hide yes)
			(effects
				(font
					(size 1.016 1.016)
					(thickness 0.1524)
				)
			)
		)
		(property "Device Type" "R1206H26"
			(at 0 -6.3754 0)
			(unlocked yes)
			(layer "F.Fab")
			(hide yes)
			(effects
				(font
					(size 1.016 1.016)
					(thickness 0.1524)
				)
			)
		)
		(duplicate_pad_numbers_are_jumpers no)
		(fp_line
			(start -1.016 -2.2352)
			(end 1.016 -2.2352)
			(stroke
				(width 0.1524)
				(type default)
			)
			(layer "F.SilkS")
		)
		(fp_line
			(start -1.016 2.2352)
			(end -1.016 -2.2352)
			(stroke
				(width 0.1524)
				(type default)
			)
			(layer "F.SilkS")
		)
		(fp_line
			(start 1.016 -2.2352)
			(end 1.016 2.2352)
			(stroke
				(width 0.1524)
				(type default)
			)
			(layer "F.SilkS")
		)
		(fp_line
			(start 1.016 2.2352)
			(end -1.016 2.2352)
			(stroke
				(width 0.1524)
				(type default)
			)
			(layer "F.SilkS")
		)
		(fp_rect
			(start -1.0922 2.3114)
			(end 1.0922 -2.3114)
			(stroke
				(width 0)
				(type default)
			)
			(fill no)
			(layer "F.CrtYd")
		)
		(fp_poly
			(pts
				(xy -1.0922 -2.3114) (xy 1.0922 -2.3114) (xy 1.0922 2.3114) (xy -1.0922 2.3114)
			)
			(stroke
				(width 0)
				(type default)
			)
			(fill no)
			(layer "F.Fab")
		)
		(pad "1" smd rect
			(at 0 -1.397)
			(size 1.651 1.27)
			(layers "F.Cu" "F.Mask" "F.Paste")
			(net "P5V_HDD3")
		)
		(pad "2" smd rect
			(at 0 1.397)
			(size 1.651 1.27)
			(layers "F.Cu" "F.Mask" "F.Paste")
			(net "5V_PRE_3")
		)
	)
	(footprint ""
		(layer "F.Cu")
		(at 165.732968 -97.328228 -90)
		(property "Reference" "R398"
			(at 0 0 270)
			(layer "F.SilkS")
			(hide yes)
			(effects
				(font
					(size 1.27 1.27)
				)
			)
		)
		(property "Value" "4K7R2F-GP"
			(at 0.064008 -3.993896 270)
			(unlocked yes)
			(layer "F.Fab")
			(hide yes)
			(effects
				(font
					(size 1.016 1.016)
					(thickness 0.1524)
				)
			)
		)
		(property "Device Type" "R402H16"
			(at 0.064008 -5.517896 270)
			(unlocked yes)
			(layer "F.Fab")
			(hide yes)
			(effects
				(font
					(size 1.016 1.016)
					(thickness 0.1524)
				)
			)
		)
		(duplicate_pad_numbers_are_jumpers no)
		(fp_line
			(start -0.508 -0.9398)
			(end -0.508 0.9398)
			(stroke
				(width 0.1524)
				(type default)
			)
			(layer "F.SilkS")
		)
		(fp_line
			(start 0.508 -0.9398)
			(end -0.508 -0.9398)
			(stroke
				(width 0.1524)
				(type default)
			)
			(layer "F.SilkS")
		)
		(fp_rect
			(start -0.508 0.9398)
			(end 0.508 -0.9398)
			(stroke
				(width 0)
				(type default)
			)
			(fill no)
			(layer "F.CrtYd")
		)
		(fp_rect
			(start -0.508 0.9398)
			(end 0.508 -0.9398)
			(stroke
				(width 0)
				(type default)
			)
			(fill no)
			(layer "F.Fab")
		)
		(pad "1" smd custom
			(at 0 -0.4445 270)
			(size 0.1397 0.1397)
			(layers "F.Cu" "F.Mask" "F.Paste")
			(net "DRIVE_B_17_ACT")
			(options
				(clearance outline)
				(anchor circle)
			)
			(primitives
				(gr_poly
					(pts
						(arc
							(start -0.1778 -0.2794)
							(mid -0.249642 -0.249642)
							(end -0.2794 -0.1778)
						)
						(arc
							(start -0.2794 0.1778)
							(mid -0.249642 0.249642)
							(end -0.1778 0.2794)
						)
						(arc
							(start 0.1778 0.2794)
							(mid 0.249642 0.249642)
							(end 0.2794 0.1778)
						)
						(arc
							(start 0.2794 -0.1778)
							(mid 0.249642 -0.249642)
							(end 0.1778 -0.2794)
						)
					)
					(width 0)
					(fill yes)
				)
			)
		)
		(pad "2" smd custom
			(at 0 0.4445 270)
			(size 0.1397 0.1397)
			(layers "F.Cu" "F.Mask" "F.Paste")
			(net "GND")
			(options
				(clearance outline)
				(anchor circle)
			)
			(primitives
				(gr_poly
					(pts
						(arc
							(start -0.1778 -0.2794)
							(mid -0.249642 -0.249642)
							(end -0.2794 -0.1778)
						)
						(arc
							(start -0.2794 0.1778)
							(mid -0.249642 0.249642)
							(end -0.1778 0.2794)
						)
						(arc
							(start 0.1778 0.2794)
							(mid 0.249642 0.249642)
							(end 0.2794 0.1778)
						)
						(arc
							(start 0.2794 -0.1778)
							(mid 0.249642 -0.249642)
							(end 0.1778 -0.2794)
						)
					)
					(width 0)
					(fill yes)
				)
			)
		)
	)
)
